# BASEBOARD_FAB2 (Tioga Pass) — schematic netlist excerpt (pin names and nets, part order shuffled) for the footprints in the layout excerpt that follows; sources: Cadence DE-HDL packaged netlist, KiCad conversion of Wiwynn_Tioga_Pass_MB.brd

R9U12  RES  0.0 5% CHIP  pkg 0402  page 224 : A = VR_PVDDQ_GHJ_PH2_VCIN ; B = P5V_STBY
C1D5  SC1U10V2KX-4-GP  10%  pkg SMD-BCG6  page 208 : \1\ = P5V_STBY ; \2\ = GND

U8D8  TPS3700  IC  pkg SM  page 196
  OUTB  = PWRGD_P5V_N
  VDD  = P3V3_STBY
  INBN  = A_PG_P5V
  INAP  = A_PG_P12V_MAIN
  GND  = GND
  OUTA  = PWRGD_P12V_MAIN_R

(kicad_pcb
	(version 20260206)
	(generator "pcbnew")
	(generator_version "10.0")
	(general
		(thickness 1.6)
		(legacy_teardrops no)
	)
	(paper "A4")
	(title_block
		(title "Wiwynn_Tioga_Pass_MB.brd")
		(comment 1 "Tioga Pass / footprints 3694-3696 of 4770")
	)
	(layers
		(0 "F.Cu" signal "TOP")
		(4 "In1.Cu" signal "L2GND")
		(6 "In2.Cu" signal "L3")
		(8 "In3.Cu" signal "L4GND")
		(10 "In4.Cu" signal "L5")
		(12 "In5.Cu" signal "L6GND")
		(14 "In6.Cu" signal "L7VCC")
		(16 "In7.Cu" signal "L8VCC")
		(18 "In8.Cu" signal "L9GND")
		(20 "In9.Cu" signal "L10")
		(22 "In10.Cu" signal "L11GND")
		(24 "In11.Cu" signal "L12")
		(26 "In12.Cu" signal "L13GND")
		(2 "B.Cu" signal "BOTTOM")
		(9 "F.Adhes" user "F.Adhesive")
		(11 "B.Adhes" user "B.Adhesive")
		(13 "F.Paste" user "Package Geometry/Pastemask Top")
		(15 "B.Paste" user "Package Geometry/Pastemask Bottom")
		(5 "F.SilkS" user "Ref Des/Silkscreen Top")
		(7 "B.SilkS" user "Ref Des/Silkscreen Bottom")
		(1 "F.Mask" user "Board Geometry/Soldermask Top")
		(3 "B.Mask" user "Board Geometry/Soldermask Bottom")
		(17 "Dwgs.User" user "User.Drawings")
		(19 "Cmts.User" user "User.Comments")
		(21 "Eco1.User" user "User.Eco1")
		(23 "Eco2.User" user "User.Eco2")
		(25 "Edge.Cuts" user "Board Geometry/Outline")
		(27 "Margin" user)
		(31 "F.CrtYd" user "Package Geometry/Place Bound Top")
		(29 "B.CrtYd" user "Package Geometry/Place Bound Bottom")
		(35 "F.Fab" user "Ref Des/Assembly Top")
		(33 "B.Fab" user "Ref Des/Assembly Bottom")
	)
	(footprint ""
		(layer "B.Cu")
		(at 410.455872 -6.0452 -90)
		(property "Reference" "U8D8"
			(at -0.621538 1.822958 90)
			(unlocked yes)
			(layer "B.SilkS")
			(effects
				(font
					(size 0.7874 0.5842)
					(thickness 0.1524)
				)
				(justify mirror)
			)
		)
		(property "Value" ""
			(at 0 0 90)
			(layer "B.Fab")
			(effects
				(font
					(size 1.27 1.27)
				)
				(justify mirror)
			)
		)
		(duplicate_pad_numbers_are_jumpers no)
		(fp_circle
			(center 1.0795 -0.054102)
			(end 1.0795 -0.180848)
			(stroke
				(width 0.254)
				(type default)
			)
			(fill no)
			(layer "B.SilkS")
		)
		(fp_rect
			(start 0.216154 1.27508)
			(end -1.333754 -0.275082)
			(stroke
				(width 0)
				(type default)
			)
			(fill no)
			(layer "B.CrtYd")
		)
		(fp_line
			(start -1.333754 1.27508)
			(end 0.216154 1.27508)
			(stroke
				(width 0.1)
				(type default)
			)
			(layer "B.Fab")
		)
		(fp_line
			(start 0.216154 1.27508)
			(end 0.216154 -0.275082)
			(stroke
				(width 0.1)
				(type default)
			)
			(layer "B.Fab")
		)
		(fp_line
			(start -1.333754 -0.275082)
			(end -1.333754 1.27508)
			(stroke
				(width 0.1)
				(type default)
			)
			(layer "B.Fab")
		)
		(fp_line
			(start 0.216154 -0.275082)
			(end -1.333754 -0.275082)
			(stroke
				(width 0.1)
				(type default)
			)
			(layer "B.Fab")
		)
		(fp_circle
			(center 1.0795 -0.054102)
			(end 1.0795 -0.180848)
			(stroke
				(width 0.254)
				(type default)
			)
			(fill no)
			(layer "B.Fab")
		)
		(pad "1" smd rect
			(at 0 0 90)
			(size 0.9398 0.3048)
			(layers "B.Cu" "B.Mask" "B.Paste")
			(net "PWRGD_P5V_N")
		)
		(pad "2" smd rect
			(at 0.0254 0.500126 90)
			(size 0.889 0.3048)
			(layers "B.Cu" "B.Mask" "B.Paste")
			(net "P3V3_STBY")
		)
		(pad "3" smd rect
			(at 0.0254 0.999998 90)
			(size 0.889 0.3048)
			(layers "B.Cu" "B.Mask" "B.Paste")
			(net "A_PG_P5V")
		)
		(pad "4" smd rect
			(at -1.143 0.999998 90)
			(size 0.889 0.3048)
			(layers "B.Cu" "B.Mask" "B.Paste")
			(net "A_PG_P12V_MAIN")
		)
		(pad "5" smd rect
			(at -1.143 0.500126 90)
			(size 0.889 0.3048)
			(layers "B.Cu" "B.Mask" "B.Paste")
			(net "GND")
		)
		(pad "6" smd rect
			(at -1.143 0 90)
			(size 0.889 0.3048)
			(layers "B.Cu" "B.Mask" "B.Paste")
			(net "PWRGD_P12V_MAIN_R")
		)
	)
	(footprint ""
		(layer "B.Cu")
		(at 3.499104 -15.15237 90)
		(property "Reference" "R9U12"
			(at 0 0 90)
			(layer "B.SilkS")
			(hide yes)
			(effects
				(font
					(size 1.27 1.27)
				)
				(justify mirror)
			)
		)
		(property "Value" ""
			(at 0 0 90)
			(layer "B.Fab")
			(effects
				(font
					(size 1.27 1.27)
				)
				(justify mirror)
			)
		)
		(duplicate_pad_numbers_are_jumpers no)
		(fp_rect
			(start 0.2794 -0.1016)
			(end -0.2794 0.9906)
			(stroke
				(width 0)
				(type default)
			)
			(fill no)
			(layer "B.CrtYd")
		)
		(fp_line
			(start 0.2794 -0.1016)
			(end 0.2794 0.9906)
			(stroke
				(width 0.1)
				(type default)
			)
			(layer "B.Fab")
		)
		(fp_line
			(start -0.2794 -0.1016)
			(end 0.2794 -0.1016)
			(stroke
				(width 0.1)
				(type default)
			)
			(layer "B.Fab")
		)
		(fp_line
			(start 0.2794 0.9906)
			(end -0.2794 0.9906)
			(stroke
				(width 0.1)
				(type default)
			)
			(layer "B.Fab")
		)
		(fp_line
			(start -0.2794 0.9906)
			(end -0.2794 -0.1016)
			(stroke
				(width 0.1)
				(type default)
			)
			(layer "B.Fab")
		)
		(pad "1" smd rect
			(at 0 0 270)
			(size 0.508 0.508)
			(layers "B.Cu" "B.Mask" "B.Paste")
			(net "VR_PVDDQ_GHJ_PH2_VCIN")
		)
		(pad "2" smd rect
			(at 0 0.889 270)
			(size 0.508 0.508)
			(layers "B.Cu" "B.Mask" "B.Paste")
			(net "P5V_STBY")
		)
		(zone
			(layer "B.Cu")
			(hatch none 0.5)
			(connect_pads
				(clearance 0)
			)
			(min_thickness 0.25)
			(keepout
				(tracks not_allowed)
				(vias allowed)
				(pads allowed)
				(copperpour not_allowed)
				(footprints allowed)
			)
			(placement
				(enabled no)
				(sheetname "")
			)
			(fill
				(thermal_gap 0.5)
				(thermal_bridge_width 0.5)
				(island_removal_mode 0)
			)
			(polygon
				(pts
					(xy 3.753104 -15.40637) (xy 3.753104 -14.89837) (xy 4.134104 -14.89837) (xy 4.134104 -15.40637)
				)
			)
		)
		(zone
			(layer "B.Cu")
			(hatch none 0.5)
			(connect_pads
				(clearance 0)
			)
			(min_thickness 0.25)
			(keepout
				(tracks allowed)
				(vias not_allowed)
				(pads allowed)
				(copperpour not_allowed)
				(footprints allowed)
			)
			(placement
				(enabled no)
				(sheetname "")
			)
			(fill
				(thermal_gap 0.5)
				(thermal_bridge_width 0.5)
				(island_removal_mode 0)
			)
			(polygon
				(pts
					(xy 3.753104 -15.40637) (xy 3.753104 -14.89837) (xy 4.134104 -14.89837) (xy 4.134104 -15.40637)
				)
			)
		)
	)
	(footprint ""
		(layer "B.Cu")
		(at 33.622996 -77.552042 90)
		(property "Reference" "C1D5"
			(at 0 0 90)
			(layer "B.SilkS")
			(hide yes)
			(effects
				(font
					(size 1.27 1.27)
				)
				(justify mirror)
			)
		)
		(property "Value" "*"
			(at -1.1811 -2.8194 90)
			(unlocked yes)
			(layer "B.Fab")
			(hide yes)
			(effects
				(font
					(size 1.27 1.016)
					(thickness 0.1524)
				)
				(justify mirror)
			)
		)
		(property "Device Type" "SC1U10V2KX-4-GP_SMD-BCG6-SC1U1A"
			(at -1.1811 -4.3434 90)
			(unlocked yes)
			(layer "B.Fab")
			(hide yes)
			(effects
				(font
					(size 1.27 1.016)
					(thickness 0.1524)
				)
				(justify mirror)
			)
		)
		(duplicate_pad_numbers_are_jumpers no)
		(fp_rect
			(start 0.4318 0.9525)
			(end -0.4318 -0.9525)
			(stroke
				(width 0)
				(type default)
			)
			(fill no)
			(layer "B.CrtYd")
		)
		(fp_rect
			(start 0.4318 0.9525)
			(end -0.4318 -0.9525)
			(stroke
				(width 0)
				(type default)
			)
			(fill no)
			(layer "B.Fab")
		)
		(pad "1" smd custom
			(at 0 -0.4445 270)
			(size 0.1524 0.1524)
			(layers "B.Cu" "B.Mask" "B.Paste")
			(net "P5V_STBY")
			(options
				(clearance outline)
				(anchor circle)
			)
			(primitives
				(gr_poly
					(pts
						(arc
							(start 0.3048 0.2032)
							(mid 0.275042 0.275042)
							(end 0.2032 0.3048)
						)
						(arc
							(start -0.2032 0.3048)
							(mid -0.275042 0.275042)
							(end -0.3048 0.2032)
						)
						(arc
							(start -0.3048 -0.2032)
							(mid -0.275042 -0.275042)
							(end -0.2032 -0.3048)
						)
						(arc
							(start 0.2032 -0.3048)
							(mid 0.275042 -0.275042)
							(end 0.3048 -0.2032)
						)
					)
					(width 0)
					(fill yes)
				)
			)
		)
		(pad "2" smd custom
			(at 0 0.4445 270)
			(size 0.1524 0.1524)
			(layers "B.Cu" "B.Mask" "B.Paste")
			(net "GND")
			(options
				(clearance outline)
				(anchor circle)
			)
			(primitives
				(gr_poly
					(pts
						(arc
							(start 0.3048 0.2032)
							(mid 0.275042 0.275042)
							(end 0.2032 0.3048)
						)
						(arc
							(start -0.2032 0.3048)
							(mid -0.275042 0.275042)
							(end -0.3048 0.2032)
						)
						(arc
							(start -0.3048 -0.2032)
							(mid -0.275042 -0.275042)
							(end -0.2032 -0.3048)
						)
						(arc
							(start 0.2032 -0.3048)
							(mid 0.275042 -0.275042)
							(end 0.3048 -0.2032)
						)
					)
					(width 0)
					(fill yes)
				)
			)
		)
	)
)
